(kicad_pcb
	(version 20260206)
	(generator "pcbnew")
	(generator_version "10.0")
	(general
		(thickness 1.6)
		(legacy_teardrops no)
	)
	(paper "A4")
	(title_block
		(title "03242023_DA0F0TMBIJ0_F0T_Motherboard_J_brd_V01_OCP.brd")
		(comment 1 "Grand Teton / footprints 5034-5040 of 6105")
	)
	(layers
		(0 "F.Cu" signal "TOP")
		(4 "In1.Cu" signal "GND")
		(6 "In2.Cu" signal "IN1")
		(8 "In3.Cu" signal "GND1")
		(10 "In4.Cu" signal "IN2")
		(12 "In5.Cu" signal "GND2")
		(14 "In6.Cu" signal "IN3")
		(16 "In7.Cu" signal "GND3")
		(18 "In8.Cu" signal "VCC")
		(20 "In9.Cu" signal "VCC1")
		(22 "In10.Cu" signal "GND4")
		(24 "In11.Cu" signal "IN4")
		(26 "In12.Cu" signal "GND5")
		(28 "In13.Cu" signal "IN5")
		(30 "In14.Cu" signal "GND6")
		(32 "In15.Cu" signal "IN6")
		(34 "In16.Cu" signal "GND7")
		(2 "B.Cu" signal "BOTTOM")
		(9 "F.Adhes" user "F.Adhesive")
		(11 "B.Adhes" user "B.Adhesive")
		(13 "F.Paste" user "Package Geometry/Pastemask Top")
		(15 "B.Paste" user "Package Geometry/Pastemask Bottom")
		(5 "F.SilkS" user "Ref Des/Silkscreen Top")
		(7 "B.SilkS" user "Ref Des/Silkscreen Bottom")
		(1 "F.Mask" user "Board Geometry/Soldermask Top")
		(3 "B.Mask" user "Board Geometry/Soldermask Bottom")
		(17 "Dwgs.User" user "User.Drawings")
		(19 "Cmts.User" user "User.Comments")
		(21 "Eco1.User" user "User.Eco1")
		(23 "Eco2.User" user "User.Eco2")
		(25 "Edge.Cuts" user "Board Geometry/Outline")
		(27 "Margin" user)
		(31 "F.CrtYd" user "Package Geometry/Place Bound Top")
		(29 "B.CrtYd" user "Package Geometry/Place Bound Bottom")
		(35 "F.Fab" user "Ref Des/Assembly Top")
		(33 "B.Fab" user "Ref Des/Assembly Bottom")
	)
	(footprint ""
		(layer "B.Cu")
		(at 118.18112 -259.53212 90)
		(property "Reference" "C449"
			(at 0 0 90)
			(layer "B.SilkS")
			(hide yes)
			(effects
				(font
					(size 1.27 1.27)
				)
				(justify mirror)
			)
		)
		(property "Value" ""
			(at 0 0 90)
			(layer "B.Fab")
			(effects
				(font
					(size 1.27 1.27)
				)
				(justify mirror)
			)
		)
		(duplicate_pad_numbers_are_jumpers no)
		(fp_line
			(start 1.524 -0.762)
			(end -1.524 -0.762)
			(stroke
				(width 0.1524)
				(type default)
			)
			(layer "B.SilkS")
		)
		(fp_line
			(start -1.524 -0.762)
			(end -1.524 0.762)
			(stroke
				(width 0.1524)
				(type default)
			)
			(layer "B.SilkS")
		)
		(fp_line
			(start 1.524 0.762)
			(end 1.524 -0.762)
			(stroke
				(width 0.1524)
				(type default)
			)
			(layer "B.SilkS")
		)
		(fp_line
			(start -1.524 0.762)
			(end 1.524 0.762)
			(stroke
				(width 0.1524)
				(type default)
			)
			(layer "B.SilkS")
		)
		(fp_line
			(start 1.1049 -0.724916)
			(end 1.1049 0.724916)
			(stroke
				(width 0.1)
				(type default)
			)
			(layer "B.Fab")
		)
		(fp_line
			(start -1.1049 -0.724916)
			(end 1.1049 -0.724916)
			(stroke
				(width 0.1)
				(type default)
			)
			(layer "B.Fab")
		)
		(fp_line
			(start 1.1049 0.724916)
			(end -1.1049 0.724916)
			(stroke
				(width 0.1)
				(type default)
			)
			(layer "B.Fab")
		)
		(fp_line
			(start -1.1049 0.724916)
			(end -1.1049 -0.724916)
			(stroke
				(width 0.1)
				(type default)
			)
			(layer "B.Fab")
		)
		(pad "1" smd rect
			(at 0.889 0 90)
			(size 1.016 1.27)
			(layers "B.Cu" "B.Mask" "B.Paste")
			(net "PVCCFA_EHV_FIVRA_CPU1")
		)
		(pad "2" smd rect
			(at -0.889 0 90)
			(size 1.016 1.27)
			(layers "B.Cu" "B.Mask" "B.Paste")
			(net "GND")
		)
	)
	(footprint ""
		(layer "B.Cu")
		(at 168.83888 -101.564948 180)
		(property "Reference" "R3346"
			(at 0 0 0)
			(layer "B.SilkS")
			(hide yes)
			(effects
				(font
					(size 1.27 1.27)
				)
				(justify mirror)
			)
		)
		(property "Value" ""
			(at 0 0 0)
			(layer "B.Fab")
			(effects
				(font
					(size 1.27 1.27)
				)
				(justify mirror)
			)
		)
		(duplicate_pad_numbers_are_jumpers no)
		(fp_line
			(start 1.2954 0.5842)
			(end 1.2954 -0.5842)
			(stroke
				(width 0.1524)
				(type default)
			)
			(layer "B.SilkS")
		)
		(fp_line
			(start 1.2954 -0.5842)
			(end -1.2954 -0.5842)
			(stroke
				(width 0.1524)
				(type default)
			)
			(layer "B.SilkS")
		)
		(fp_line
			(start -1.2954 0.5842)
			(end 1.2954 0.5842)
			(stroke
				(width 0.1524)
				(type default)
			)
			(layer "B.SilkS")
		)
		(fp_line
			(start -1.2954 -0.5842)
			(end -1.2954 0.5842)
			(stroke
				(width 0.1524)
				(type default)
			)
			(layer "B.SilkS")
		)
		(fp_line
			(start 1.1938 0.4064)
			(end 1.1938 -0.406654)
			(stroke
				(width 0.1)
				(type default)
			)
			(layer "B.Fab")
		)
		(fp_line
			(start 1.1938 -0.406654)
			(end 0.8636 -0.406654)
			(stroke
				(width 0.1)
				(type default)
			)
			(layer "B.Fab")
		)
		(fp_line
			(start 0.8636 0.4572)
			(end 0.8636 0.4318)
			(stroke
				(width 0.1)
				(type default)
			)
			(layer "B.Fab")
		)
		(fp_line
			(start 0.8636 0.4318)
			(end 0.8636 0.4064)
			(stroke
				(width 0.1)
				(type default)
			)
			(layer "B.Fab")
		)
		(fp_line
			(start 0.8636 0.4064)
			(end 1.1938 0.4064)
			(stroke
				(width 0.1)
				(type default)
			)
			(layer "B.Fab")
		)
		(fp_line
			(start 0.8636 -0.406654)
			(end 0.8636 -0.4572)
			(stroke
				(width 0.1)
				(type default)
			)
			(layer "B.Fab")
		)
		(fp_line
			(start 0.8636 -0.4572)
			(end -0.8636 -0.4572)
			(stroke
				(width 0.1)
				(type default)
			)
			(layer "B.Fab")
		)
		(fp_line
			(start -0.8636 0.4572)
			(end 0.8636 0.4572)
			(stroke
				(width 0.1)
				(type default)
			)
			(layer "B.Fab")
		)
		(fp_line
			(start -0.8636 0.4064)
			(end -0.8636 0.4572)
			(stroke
				(width 0.1)
				(type default)
			)
			(layer "B.Fab")
		)
		(fp_line
			(start -0.8636 -0.406654)
			(end -1.1938 -0.406654)
			(stroke
				(width 0.1)
				(type default)
			)
			(layer "B.Fab")
		)
		(fp_line
			(start -0.8636 -0.4572)
			(end -0.8636 -0.406654)
			(stroke
				(width 0.1)
				(type default)
			)
			(layer "B.Fab")
		)
		(fp_line
			(start -1.1938 0.4064)
			(end -0.8636 0.4064)
			(stroke
				(width 0.1)
				(type default)
			)
			(layer "B.Fab")
		)
		(fp_line
			(start -1.1938 -0.406654)
			(end -1.1938 0.4064)
			(stroke
				(width 0.1)
				(type default)
			)
			(layer "B.Fab")
		)
		(pad "1" smd rect
			(at 0.7366 0 90)
			(size 0.7112 0.8128)
			(layers "B.Cu" "B.Mask" "B.Paste")
			(net "P3V3_AUX")
		)
		(pad "2" smd rect
			(at -0.7366 0 90)
			(size 0.7112 0.8128)
			(layers "B.Cu" "B.Mask" "B.Paste")
			(net "P3V3_AUX_FPGA_VCCIO0")
		)
	)
	(footprint ""
		(layer "B.Cu")
		(at 366.098582 -210.19389)
		(property "Reference" "C530"
			(at 0 0 0)
			(layer "B.SilkS")
			(hide yes)
			(effects
				(font
					(size 1.27 1.27)
				)
				(justify mirror)
			)
		)
		(property "Value" ""
			(at 0 0 0)
			(layer "B.Fab")
			(effects
				(font
					(size 1.27 1.27)
				)
				(justify mirror)
			)
		)
		(duplicate_pad_numbers_are_jumpers no)
		(fp_line
			(start -1.524 -0.762)
			(end -1.524 0.762)
			(stroke
				(width 0.1524)
				(type default)
			)
			(layer "B.SilkS")
		)
		(fp_line
			(start -1.524 0.762)
			(end 1.524 0.762)
			(stroke
				(width 0.1524)
				(type default)
			)
			(layer "B.SilkS")
		)
		(fp_line
			(start 1.524 -0.762)
			(end -1.524 -0.762)
			(stroke
				(width 0.1524)
				(type default)
			)
			(layer "B.SilkS")
		)
		(fp_line
			(start 1.524 0.762)
			(end 1.524 -0.762)
			(stroke
				(width 0.1524)
				(type default)
			)
			(layer "B.SilkS")
		)
		(fp_line
			(start -1.1049 -0.724916)
			(end 1.1049 -0.724916)
			(stroke
				(width 0.1)
				(type default)
			)
			(layer "B.Fab")
		)
		(fp_line
			(start -1.1049 0.724916)
			(end -1.1049 -0.724916)
			(stroke
				(width 0.1)
				(type default)
			)
			(layer "B.Fab")
		)
		(fp_line
			(start 1.1049 -0.724916)
			(end 1.1049 0.724916)
			(stroke
				(width 0.1)
				(type default)
			)
			(layer "B.Fab")
		)
		(fp_line
			(start 1.1049 0.724916)
			(end -1.1049 0.724916)
			(stroke
				(width 0.1)
				(type default)
			)
			(layer "B.Fab")
		)
		(pad "1" smd rect
			(at 0.889 0)
			(size 1.016 1.27)
			(layers "B.Cu" "B.Mask" "B.Paste")
			(net "PVCCINFAON_CPU0")
		)
		(pad "2" smd rect
			(at -0.889 0)
			(size 1.016 1.27)
			(layers "B.Cu" "B.Mask" "B.Paste")
			(net "GND")
		)
	)
	(footprint ""
		(layer "B.Cu")
		(at 56.289702 -358.12349 180)
		(property "Reference" "PC1680"
			(at 0 0 0)
			(layer "B.SilkS")
			(hide yes)
			(effects
				(font
					(size 1.27 1.27)
				)
				(justify mirror)
			)
		)
		(property "Value" ""
			(at 0 0 0)
			(layer "B.Fab")
			(effects
				(font
					(size 1.27 1.27)
				)
				(justify mirror)
			)
		)
		(duplicate_pad_numbers_are_jumpers no)
		(fp_line
			(start 1.524 0.762)
			(end 1.524 -0.762)
			(stroke
				(width 0.1524)
				(type default)
			)
			(layer "B.SilkS")
		)
		(fp_line
			(start 1.524 -0.762)
			(end -1.524 -0.762)
			(stroke
				(width 0.1524)
				(type default)
			)
			(layer "B.SilkS")
		)
		(fp_line
			(start -1.524 0.762)
			(end 1.524 0.762)
			(stroke
				(width 0.1524)
				(type default)
			)
			(layer "B.SilkS")
		)
		(fp_line
			(start -1.524 -0.762)
			(end -1.524 0.762)
			(stroke
				(width 0.1524)
				(type default)
			)
			(layer "B.SilkS")
		)
		(fp_line
			(start 1.1049 0.724916)
			(end -1.1049 0.724916)
			(stroke
				(width 0.1)
				(type default)
			)
			(layer "B.Fab")
		)
		(fp_line
			(start 1.1049 -0.724916)
			(end 1.1049 0.724916)
			(stroke
				(width 0.1)
				(type default)
			)
			(layer "B.Fab")
		)
		(fp_line
			(start -1.1049 0.724916)
			(end -1.1049 -0.724916)
			(stroke
				(width 0.1)
				(type default)
			)
			(layer "B.Fab")
		)
		(fp_line
			(start -1.1049 -0.724916)
			(end 1.1049 -0.724916)
			(stroke
				(width 0.1)
				(type default)
			)
			(layer "B.Fab")
		)
		(pad "1" smd rect
			(at 0.889 0 180)
			(size 1.016 1.27)
			(layers "B.Cu" "B.Mask" "B.Paste")
			(net "SW_P12V_PVCCFA_EHV_FIVRA_CPU1_L")
		)
		(pad "2" smd rect
			(at -0.889 0 180)
			(size 1.016 1.27)
			(layers "B.Cu" "B.Mask" "B.Paste")
			(net "GND")
		)
	)
	(footprint ""
		(layer "B.Cu")
		(at 258.953 -101.183948)
		(property "Reference" "C116"
			(at 0 0 0)
			(layer "B.SilkS")
			(hide yes)
			(effects
				(font
					(size 1.27 1.27)
				)
				(justify mirror)
			)
		)
		(property "Value" ""
			(at 0 0 0)
			(layer "B.Fab")
			(effects
				(font
					(size 1.27 1.27)
				)
				(justify mirror)
			)
		)
		(duplicate_pad_numbers_are_jumpers no)
		(fp_line
			(start -0.7874 -0.4064)
			(end -0.7874 0.4064)
			(stroke
				(width 0.1524)
				(type default)
			)
			(layer "B.SilkS")
		)
		(fp_line
			(start -0.7874 0.4064)
			(end 0.7874 0.4064)
			(stroke
				(width 0.1524)
				(type default)
			)
			(layer "B.SilkS")
		)
		(fp_line
			(start 0.7874 -0.4064)
			(end -0.7874 -0.4064)
			(stroke
				(width 0.1524)
				(type default)
			)
			(layer "B.SilkS")
		)
		(fp_line
			(start 0.7874 0.4064)
			(end 0.7874 -0.4064)
			(stroke
				(width 0.1524)
				(type default)
			)
			(layer "B.SilkS")
		)
		(fp_line
			(start -0.67945 -0.3048)
			(end -0.67945 0.3048)
			(stroke
				(width 0.1)
				(type default)
			)
			(layer "B.Fab")
		)
		(fp_line
			(start -0.67945 0.3048)
			(end -0.120396 0.3048)
			(stroke
				(width 0.1)
				(type default)
			)
			(layer "B.Fab")
		)
		(fp_line
			(start -0.12065 -0.3048)
			(end -0.67945 -0.3048)
			(stroke
				(width 0.1)
				(type default)
			)
			(layer "B.Fab")
		)
		(fp_line
			(start -0.12065 -0.2794)
			(end -0.12065 -0.3048)
			(stroke
				(width 0.1)
				(type default)
			)
			(layer "B.Fab")
		)
		(fp_line
			(start -0.120396 0.2794)
			(end 0.12065 0.2794)
			(stroke
				(width 0.1)
				(type default)
			)
			(layer "B.Fab")
		)
		(fp_line
			(start -0.120396 0.3048)
			(end -0.120396 0.2794)
			(stroke
				(width 0.1)
				(type default)
			)
			(layer "B.Fab")
		)
		(fp_line
			(start 0.12065 -0.305054)
			(end 0.12065 -0.2794)
			(stroke
				(width 0.1)
				(type default)
			)
			(layer "B.Fab")
		)
		(fp_line
			(start 0.12065 -0.2794)
			(end -0.12065 -0.2794)
			(stroke
				(width 0.1)
				(type default)
			)
			(layer "B.Fab")
		)
		(fp_line
			(start 0.12065 0.2794)
			(end 0.12065 0.3048)
			(stroke
				(width 0.1)
				(type default)
			)
			(layer "B.Fab")
		)
		(fp_line
			(start 0.12065 0.3048)
			(end 0.67945 0.3048)
			(stroke
				(width 0.1)
				(type default)
			)
			(layer "B.Fab")
		)
		(fp_line
			(start 0.67945 -0.305054)
			(end 0.12065 -0.305054)
			(stroke
				(width 0.1)
				(type default)
			)
			(layer "B.Fab")
		)
		(fp_line
			(start 0.67945 0.3048)
			(end 0.67945 -0.305054)
			(stroke
				(width 0.1)
				(type default)
			)
			(layer "B.Fab")
		)
		(pad "1" smd circle
			(at 0.40005 0 180)
			(size 0 0)
			(layers "B.Cu" "B.Mask" "B.Paste")
			(net "P3V3_AUX_CLK_GEN_VDDMXCK_CK440")
		)
		(pad "2" smd circle
			(at -0.40005 0 180)
			(size 0 0)
			(layers "B.Cu" "B.Mask" "B.Paste")
			(net "GND")
		)
	)
	(footprint ""
		(layer "B.Cu")
		(at 121.581926 -212.049868 180)
		(property "Reference" "C484"
			(at 0 0 0)
			(layer "B.SilkS")
			(hide yes)
			(effects
				(font
					(size 1.27 1.27)
				)
				(justify mirror)
			)
		)
		(property "Value" ""
			(at 0 0 0)
			(layer "B.Fab")
			(effects
				(font
					(size 1.27 1.27)
				)
				(justify mirror)
			)
		)
		(duplicate_pad_numbers_are_jumpers no)
		(fp_line
			(start 1.524 0.762)
			(end 1.524 -0.762)
			(stroke
				(width 0.1524)
				(type default)
			)
			(layer "B.SilkS")
		)
		(fp_line
			(start 1.524 -0.762)
			(end -1.524 -0.762)
			(stroke
				(width 0.1524)
				(type default)
			)
			(layer "B.SilkS")
		)
		(fp_line
			(start -1.524 0.762)
			(end 1.524 0.762)
			(stroke
				(width 0.1524)
				(type default)
			)
			(layer "B.SilkS")
		)
		(fp_line
			(start -1.524 -0.762)
			(end -1.524 0.762)
			(stroke
				(width 0.1524)
				(type default)
			)
			(layer "B.SilkS")
		)
		(fp_line
			(start 1.1049 0.724916)
			(end -1.1049 0.724916)
			(stroke
				(width 0.1)
				(type default)
			)
			(layer "B.Fab")
		)
		(fp_line
			(start 1.1049 -0.724916)
			(end 1.1049 0.724916)
			(stroke
				(width 0.1)
				(type default)
			)
			(layer "B.Fab")
		)
		(fp_line
			(start -1.1049 0.724916)
			(end -1.1049 -0.724916)
			(stroke
				(width 0.1)
				(type default)
			)
			(layer "B.Fab")
		)
		(fp_line
			(start -1.1049 -0.724916)
			(end 1.1049 -0.724916)
			(stroke
				(width 0.1)
				(type default)
			)
			(layer "B.Fab")
		)
		(pad "1" smd rect
			(at 0.889 0 180)
			(size 1.016 1.27)
			(layers "B.Cu" "B.Mask" "B.Paste")
			(net "PVCCINFAON_CPU1")
		)
		(pad "2" smd rect
			(at -0.889 0 180)
			(size 1.016 1.27)
			(layers "B.Cu" "B.Mask" "B.Paste")
			(net "GND")
		)
	)
	(footprint ""
		(layer "B.Cu")
		(at 89.661238 -179.31511)
		(property "Reference" "R1003"
			(at 0 0 0)
			(layer "B.SilkS")
			(hide yes)
			(effects
				(font
					(size 1.27 1.27)
				)
				(justify mirror)
			)
		)
		(property "Value" ""
			(at 0 0 0)
			(layer "B.Fab")
			(effects
				(font
					(size 1.27 1.27)
				)
				(justify mirror)
			)
		)
		(duplicate_pad_numbers_are_jumpers no)
		(fp_line
			(start -0.7874 -0.4064)
			(end -0.7874 0.4064)
			(stroke
				(width 0.1524)
				(type default)
			)
			(layer "B.SilkS")
		)
		(fp_line
			(start -0.7874 0.4064)
			(end 0.7874 0.4064)
			(stroke
				(width 0.1524)
				(type default)
			)
			(layer "B.SilkS")
		)
		(fp_line
			(start 0.7874 -0.4064)
			(end -0.7874 -0.4064)
			(stroke
				(width 0.1524)
				(type default)
			)
			(layer "B.SilkS")
		)
		(fp_line
			(start 0.7874 0.4064)
			(end 0.7874 -0.4064)
			(stroke
				(width 0.1524)
				(type default)
			)
			(layer "B.SilkS")
		)
		(fp_line
			(start -0.67945 -0.3048)
			(end -0.67945 0.3048)
			(stroke
				(width 0.1)
				(type default)
			)
			(layer "B.Fab")
		)
		(fp_line
			(start -0.67945 0.3048)
			(end -0.120396 0.3048)
			(stroke
				(width 0.1)
				(type default)
			)
			(layer "B.Fab")
		)
		(fp_line
			(start -0.12065 -0.3048)
			(end -0.67945 -0.3048)
			(stroke
				(width 0.1)
				(type default)
			)
			(layer "B.Fab")
		)
		(fp_line
			(start -0.12065 -0.2794)
			(end -0.12065 -0.3048)
			(stroke
				(width 0.1)
				(type default)
			)
			(layer "B.Fab")
		)
		(fp_line
			(start -0.120396 0.2794)
			(end 0.12065 0.2794)
			(stroke
				(width 0.1)
				(type default)
			)
			(layer "B.Fab")
		)
		(fp_line
			(start -0.120396 0.3048)
			(end -0.120396 0.2794)
			(stroke
				(width 0.1)
				(type default)
			)
			(layer "B.Fab")
		)
		(fp_line
			(start 0.12065 -0.305054)
			(end 0.12065 -0.2794)
			(stroke
				(width 0.1)
				(type default)
			)
			(layer "B.Fab")
		)
		(fp_line
			(start 0.12065 -0.2794)
			(end -0.12065 -0.2794)
			(stroke
				(width 0.1)
				(type default)
			)
			(layer "B.Fab")
		)
		(fp_line
			(start 0.12065 0.2794)
			(end 0.12065 0.3048)
			(stroke
				(width 0.1)
				(type default)
			)
			(layer "B.Fab")
		)
		(fp_line
			(start 0.12065 0.3048)
			(end 0.67945 0.3048)
			(stroke
				(width 0.1)
				(type default)
			)
			(layer "B.Fab")
		)
		(fp_line
			(start 0.67945 -0.305054)
			(end 0.12065 -0.305054)
			(stroke
				(width 0.1)
				(type default)
			)
			(layer "B.Fab")
		)
		(fp_line
			(start 0.67945 0.3048)
			(end 0.67945 -0.305054)
			(stroke
				(width 0.1)
				(type default)
			)
			(layer "B.Fab")
		)
		(pad "1" smd circle
			(at 0.40005 0 180)
			(size 0 0)
			(layers "B.Cu" "B.Mask" "B.Paste")
			(net "P3V3")
		)
		(pad "2" smd circle
			(at -0.40005 0 180)
			(size 0 0)
			(layers "B.Cu" "B.Mask" "B.Paste")
			(net "FM_SMB_CPU1_ALERT_R1")
		)
	)
)
